(kicad_pcb
	(version 20260206)
	(generator "pcbnew")
	(generator_version "10.0")
	(general
		(thickness 1.6)
		(legacy_teardrops no)
	)
	(paper "A4")
	(title_block
		(title "01162023_DA0F0TEBIF0_F0T_Expander_BD_F_brd_V02_OCP.brd")
		(comment 1 "Grand Teton / footprints 3856-3862 of 9728")
	)
	(layers
		(0 "F.Cu" signal "TOP")
		(4 "In1.Cu" signal "GND")
		(6 "In2.Cu" signal "VCC")
		(8 "In3.Cu" signal "VCC1")
		(10 "In4.Cu" signal "GND1")
		(12 "In5.Cu" signal "IN1")
		(14 "In6.Cu" signal "GND2")
		(16 "In7.Cu" signal "IN2")
		(18 "In8.Cu" signal "GND3")
		(20 "In9.Cu" signal "IN3")
		(22 "In10.Cu" signal "GND4")
		(24 "In11.Cu" signal "IN4")
		(26 "In12.Cu" signal "GND5")
		(28 "In13.Cu" signal "IN5")
		(30 "In14.Cu" signal "GND6")
		(32 "In15.Cu" signal "IN6")
		(34 "In16.Cu" signal "GND7")
		(2 "B.Cu" signal "BOTTOM")
		(9 "F.Adhes" user "F.Adhesive")
		(11 "B.Adhes" user "B.Adhesive")
		(13 "F.Paste" user "Package Geometry/Pastemask Top")
		(15 "B.Paste" user "Package Geometry/Pastemask Bottom")
		(5 "F.SilkS" user "Ref Des/Silkscreen Top")
		(7 "B.SilkS" user "Ref Des/Silkscreen Bottom")
		(1 "F.Mask" user "Board Geometry/Soldermask Top")
		(3 "B.Mask" user "Board Geometry/Soldermask Bottom")
		(17 "Dwgs.User" user "User.Drawings")
		(19 "Cmts.User" user "User.Comments")
		(21 "Eco1.User" user "User.Eco1")
		(23 "Eco2.User" user "User.Eco2")
		(25 "Edge.Cuts" user "Board Geometry/Outline")
		(27 "Margin" user)
		(31 "F.CrtYd" user "Package Geometry/Place Bound Top")
		(29 "B.CrtYd" user "Package Geometry/Place Bound Bottom")
		(35 "F.Fab" user "Ref Des/Assembly Top")
		(33 "B.Fab" user "Ref Des/Assembly Bottom")
	)
	(footprint ""
		(layer "F.Cu")
		(at 388.898384 -252.356874 -90)
		(property "Reference" "R1426"
			(at 0 0 270)
			(layer "F.SilkS")
			(hide yes)
			(effects
				(font
					(size 1.27 1.27)
				)
			)
		)
		(property "Value" ""
			(at 0 0 270)
			(layer "F.Fab")
			(effects
				(font
					(size 1.27 1.27)
				)
			)
		)
		(duplicate_pad_numbers_are_jumpers no)
		(fp_line
			(start -0.7874 0.4064)
			(end -0.7874 -0.4064)
			(stroke
				(width 0.1524)
				(type default)
			)
			(layer "F.SilkS")
		)
		(fp_line
			(start 0.7874 0.4064)
			(end -0.7874 0.4064)
			(stroke
				(width 0.1524)
				(type default)
			)
			(layer "F.SilkS")
		)
		(fp_line
			(start -0.7874 -0.4064)
			(end 0.7874 -0.4064)
			(stroke
				(width 0.1524)
				(type default)
			)
			(layer "F.SilkS")
		)
		(fp_line
			(start 0.7874 -0.4064)
			(end 0.7874 0.4064)
			(stroke
				(width 0.1524)
				(type default)
			)
			(layer "F.SilkS")
		)
		(fp_line
			(start -0.67945 0.3048)
			(end -0.67945 -0.305054)
			(stroke
				(width 0.1)
				(type default)
			)
			(layer "F.Fab")
		)
		(fp_line
			(start -0.12065 0.3048)
			(end -0.67945 0.3048)
			(stroke
				(width 0.1)
				(type default)
			)
			(layer "F.Fab")
		)
		(fp_line
			(start 0.120396 0.3048)
			(end 0.120396 0.2794)
			(stroke
				(width 0.1)
				(type default)
			)
			(layer "F.Fab")
		)
		(fp_line
			(start 0.67945 0.3048)
			(end 0.120396 0.3048)
			(stroke
				(width 0.1)
				(type default)
			)
			(layer "F.Fab")
		)
		(fp_line
			(start -0.12065 0.2794)
			(end -0.12065 0.3048)
			(stroke
				(width 0.1)
				(type default)
			)
			(layer "F.Fab")
		)
		(fp_line
			(start 0.120396 0.2794)
			(end -0.12065 0.2794)
			(stroke
				(width 0.1)
				(type default)
			)
			(layer "F.Fab")
		)
		(fp_line
			(start -0.12065 -0.2794)
			(end 0.12065 -0.2794)
			(stroke
				(width 0.1)
				(type default)
			)
			(layer "F.Fab")
		)
		(fp_line
			(start 0.12065 -0.2794)
			(end 0.12065 -0.3048)
			(stroke
				(width 0.1)
				(type default)
			)
			(layer "F.Fab")
		)
		(fp_line
			(start 0.12065 -0.3048)
			(end 0.67945 -0.3048)
			(stroke
				(width 0.1)
				(type default)
			)
			(layer "F.Fab")
		)
		(fp_line
			(start 0.67945 -0.3048)
			(end 0.67945 0.3048)
			(stroke
				(width 0.1)
				(type default)
			)
			(layer "F.Fab")
		)
		(fp_line
			(start -0.67945 -0.305054)
			(end -0.12065 -0.305054)
			(stroke
				(width 0.1)
				(type default)
			)
			(layer "F.Fab")
		)
		(fp_line
			(start -0.12065 -0.305054)
			(end -0.12065 -0.2794)
			(stroke
				(width 0.1)
				(type default)
			)
			(layer "F.Fab")
		)
		(pad "1" smd circle
			(at -0.40005 0 270)
			(size 0 0)
			(layers "F.Cu" "F.Mask" "F.Paste")
			(net "GND")
		)
		(pad "2" smd circle
			(at 0.40005 0 270)
			(size 0 0)
			(layers "F.Cu" "F.Mask" "F.Paste")
			(net "PEX3_MODE_SEL1")
		)
	)
	(footprint ""
		(layer "F.Cu")
		(at 253.028958 -79.921862)
		(property "Reference" "R1045"
			(at 0 0 0)
			(layer "F.SilkS")
			(hide yes)
			(effects
				(font
					(size 1.27 1.27)
				)
			)
		)
		(property "Value" ""
			(at 0 0 0)
			(layer "F.Fab")
			(effects
				(font
					(size 1.27 1.27)
				)
			)
		)
		(duplicate_pad_numbers_are_jumpers no)
		(fp_line
			(start -0.7874 -0.4064)
			(end 0.7874 -0.4064)
			(stroke
				(width 0.1524)
				(type default)
			)
			(layer "F.SilkS")
		)
		(fp_line
			(start -0.7874 0.4064)
			(end -0.7874 -0.4064)
			(stroke
				(width 0.1524)
				(type default)
			)
			(layer "F.SilkS")
		)
		(fp_line
			(start 0.7874 -0.4064)
			(end 0.7874 0.4064)
			(stroke
				(width 0.1524)
				(type default)
			)
			(layer "F.SilkS")
		)
		(fp_line
			(start 0.7874 0.4064)
			(end -0.7874 0.4064)
			(stroke
				(width 0.1524)
				(type default)
			)
			(layer "F.SilkS")
		)
		(fp_line
			(start -0.67945 -0.305054)
			(end -0.12065 -0.305054)
			(stroke
				(width 0.1)
				(type default)
			)
			(layer "F.Fab")
		)
		(fp_line
			(start -0.67945 0.3048)
			(end -0.67945 -0.305054)
			(stroke
				(width 0.1)
				(type default)
			)
			(layer "F.Fab")
		)
		(fp_line
			(start -0.12065 -0.305054)
			(end -0.12065 -0.2794)
			(stroke
				(width 0.1)
				(type default)
			)
			(layer "F.Fab")
		)
		(fp_line
			(start -0.12065 -0.2794)
			(end 0.12065 -0.2794)
			(stroke
				(width 0.1)
				(type default)
			)
			(layer "F.Fab")
		)
		(fp_line
			(start -0.12065 0.2794)
			(end -0.12065 0.3048)
			(stroke
				(width 0.1)
				(type default)
			)
			(layer "F.Fab")
		)
		(fp_line
			(start -0.12065 0.3048)
			(end -0.67945 0.3048)
			(stroke
				(width 0.1)
				(type default)
			)
			(layer "F.Fab")
		)
		(fp_line
			(start 0.120396 0.2794)
			(end -0.12065 0.2794)
			(stroke
				(width 0.1)
				(type default)
			)
			(layer "F.Fab")
		)
		(fp_line
			(start 0.120396 0.3048)
			(end 0.120396 0.2794)
			(stroke
				(width 0.1)
				(type default)
			)
			(layer "F.Fab")
		)
		(fp_line
			(start 0.12065 -0.3048)
			(end 0.67945 -0.3048)
			(stroke
				(width 0.1)
				(type default)
			)
			(layer "F.Fab")
		)
		(fp_line
			(start 0.12065 -0.2794)
			(end 0.12065 -0.3048)
			(stroke
				(width 0.1)
				(type default)
			)
			(layer "F.Fab")
		)
		(fp_line
			(start 0.67945 -0.3048)
			(end 0.67945 0.3048)
			(stroke
				(width 0.1)
				(type default)
			)
			(layer "F.Fab")
		)
		(fp_line
			(start 0.67945 0.3048)
			(end 0.120396 0.3048)
			(stroke
				(width 0.1)
				(type default)
			)
			(layer "F.Fab")
		)
		(pad "1" smd circle
			(at -0.40005 0)
			(size 0 0)
			(layers "F.Cu" "F.Mask" "F.Paste")
			(net "XTAL_CK440_25M_R_XIN")
		)
		(pad "2" smd circle
			(at 0.40005 0)
			(size 0 0)
			(layers "F.Cu" "F.Mask" "F.Paste")
			(net "XTAL_CK440_25M_XIN")
		)
	)
	(footprint ""
		(layer "F.Cu")
		(at 130.4544 -135.993632 -90)
		(property "Reference" "PC332"
			(at 0 0 270)
			(layer "F.SilkS")
			(hide yes)
			(effects
				(font
					(size 1.27 1.27)
				)
			)
		)
		(property "Value" ""
			(at 0 0 270)
			(layer "F.Fab")
			(effects
				(font
					(size 1.27 1.27)
				)
			)
		)
		(duplicate_pad_numbers_are_jumpers no)
		(fp_line
			(start -0.7874 0.4064)
			(end -0.7874 -0.4064)
			(stroke
				(width 0.1524)
				(type default)
			)
			(layer "F.SilkS")
		)
		(fp_line
			(start 0.7874 0.4064)
			(end -0.7874 0.4064)
			(stroke
				(width 0.1524)
				(type default)
			)
			(layer "F.SilkS")
		)
		(fp_line
			(start -0.7874 -0.4064)
			(end 0.7874 -0.4064)
			(stroke
				(width 0.1524)
				(type default)
			)
			(layer "F.SilkS")
		)
		(fp_line
			(start 0.7874 -0.4064)
			(end 0.7874 0.4064)
			(stroke
				(width 0.1524)
				(type default)
			)
			(layer "F.SilkS")
		)
		(fp_line
			(start -0.67945 0.3048)
			(end -0.67945 -0.305054)
			(stroke
				(width 0.1)
				(type default)
			)
			(layer "F.Fab")
		)
		(fp_line
			(start -0.12065 0.3048)
			(end -0.67945 0.3048)
			(stroke
				(width 0.1)
				(type default)
			)
			(layer "F.Fab")
		)
		(fp_line
			(start 0.120396 0.3048)
			(end 0.120396 0.2794)
			(stroke
				(width 0.1)
				(type default)
			)
			(layer "F.Fab")
		)
		(fp_line
			(start 0.67945 0.3048)
			(end 0.120396 0.3048)
			(stroke
				(width 0.1)
				(type default)
			)
			(layer "F.Fab")
		)
		(fp_line
			(start -0.12065 0.2794)
			(end -0.12065 0.3048)
			(stroke
				(width 0.1)
				(type default)
			)
			(layer "F.Fab")
		)
		(fp_line
			(start 0.120396 0.2794)
			(end -0.12065 0.2794)
			(stroke
				(width 0.1)
				(type default)
			)
			(layer "F.Fab")
		)
		(fp_line
			(start -0.12065 -0.2794)
			(end 0.12065 -0.2794)
			(stroke
				(width 0.1)
				(type default)
			)
			(layer "F.Fab")
		)
		(fp_line
			(start 0.12065 -0.2794)
			(end 0.12065 -0.3048)
			(stroke
				(width 0.1)
				(type default)
			)
			(layer "F.Fab")
		)
		(fp_line
			(start 0.12065 -0.3048)
			(end 0.67945 -0.3048)
			(stroke
				(width 0.1)
				(type default)
			)
			(layer "F.Fab")
		)
		(fp_line
			(start 0.67945 -0.3048)
			(end 0.67945 0.3048)
			(stroke
				(width 0.1)
				(type default)
			)
			(layer "F.Fab")
		)
		(fp_line
			(start -0.67945 -0.305054)
			(end -0.12065 -0.305054)
			(stroke
				(width 0.1)
				(type default)
			)
			(layer "F.Fab")
		)
		(fp_line
			(start -0.12065 -0.305054)
			(end -0.12065 -0.2794)
			(stroke
				(width 0.1)
				(type default)
			)
			(layer "F.Fab")
		)
		(pad "1" smd circle
			(at -0.40005 0 270)
			(size 0 0)
			(layers "F.Cu" "F.Mask" "F.Paste")
			(net "P12V_NIC2_R")
		)
		(pad "2" smd circle
			(at 0.40005 0 270)
			(size 0 0)
			(layers "F.Cu" "F.Mask" "F.Paste")
			(net "GND")
		)
	)
	(footprint ""
		(layer "F.Cu")
		(at 22.10435 -168.682416)
		(property "Reference" "PC16"
			(at 0 0 0)
			(layer "F.SilkS")
			(hide yes)
			(effects
				(font
					(size 1.27 1.27)
				)
			)
		)
		(property "Value" ""
			(at 0 0 0)
			(layer "F.Fab")
			(effects
				(font
					(size 1.27 1.27)
				)
			)
		)
		(duplicate_pad_numbers_are_jumpers no)
		(fp_line
			(start -1.524 -0.762)
			(end 1.524 -0.762)
			(stroke
				(width 0.1524)
				(type default)
			)
			(layer "F.SilkS")
		)
		(fp_line
			(start -1.524 0.762)
			(end -1.524 -0.762)
			(stroke
				(width 0.1524)
				(type default)
			)
			(layer "F.SilkS")
		)
		(fp_line
			(start 1.524 -0.762)
			(end 1.524 0.762)
			(stroke
				(width 0.1524)
				(type default)
			)
			(layer "F.SilkS")
		)
		(fp_line
			(start 1.524 0.762)
			(end -1.524 0.762)
			(stroke
				(width 0.1524)
				(type default)
			)
			(layer "F.SilkS")
		)
		(fp_line
			(start -1.1049 -0.724916)
			(end -1.1049 0.724916)
			(stroke
				(width 0.1)
				(type default)
			)
			(layer "F.Fab")
		)
		(fp_line
			(start -1.1049 0.724916)
			(end 1.1049 0.724916)
			(stroke
				(width 0.1)
				(type default)
			)
			(layer "F.Fab")
		)
		(fp_line
			(start 1.1049 -0.724916)
			(end -1.1049 -0.724916)
			(stroke
				(width 0.1)
				(type default)
			)
			(layer "F.Fab")
		)
		(fp_line
			(start 1.1049 0.724916)
			(end 1.1049 -0.724916)
			(stroke
				(width 0.1)
				(type default)
			)
			(layer "F.Fab")
		)
		(pad "1" smd rect
			(at -0.889 0 180)
			(size 1.016 1.27)
			(layers "F.Cu" "F.Mask" "F.Paste")
			(net "SW_P12V_P5V_AUX_FLT")
		)
		(pad "2" smd rect
			(at 0.889 0 180)
			(size 1.016 1.27)
			(layers "F.Cu" "F.Mask" "F.Paste")
			(net "GND")
		)
	)
	(footprint ""
		(layer "F.Cu")
		(at 119.696484 -271.703546 -90)
		(property "Reference" "PC97"
			(at 0 0 270)
			(layer "F.SilkS")
			(hide yes)
			(effects
				(font
					(size 1.27 1.27)
				)
			)
		)
		(property "Value" ""
			(at 0 0 270)
			(layer "F.Fab")
			(effects
				(font
					(size 1.27 1.27)
				)
			)
		)
		(duplicate_pad_numbers_are_jumpers no)
		(fp_line
			(start -2.146046 3.400044)
			(end -3.400044 2.146046)
			(stroke
				(width 0.1524)
				(type default)
			)
			(layer "F.SilkS")
		)
		(fp_line
			(start 3.400044 3.400044)
			(end -2.146046 3.400044)
			(stroke
				(width 0.1524)
				(type default)
			)
			(layer "F.SilkS")
		)
		(fp_line
			(start -3.400044 2.146046)
			(end -3.400044 0.9398)
			(stroke
				(width 0.1524)
				(type default)
			)
			(layer "F.SilkS")
		)
		(fp_line
			(start 3.400044 0.9398)
			(end 3.400044 3.400044)
			(stroke
				(width 0.1524)
				(type default)
			)
			(layer "F.SilkS")
		)
		(fp_line
			(start 3.400044 -0.9398)
			(end 3.400044 -3.400044)
			(stroke
				(width 0.1524)
				(type default)
			)
			(layer "F.SilkS")
		)
		(fp_line
			(start -3.400044 -2.146046)
			(end -3.400044 -0.9398)
			(stroke
				(width 0.1524)
				(type default)
			)
			(layer "F.SilkS")
		)
		(fp_line
			(start -2.146046 -3.400044)
			(end -3.400044 -2.146046)
			(stroke
				(width 0.1524)
				(type default)
			)
			(layer "F.SilkS")
		)
		(fp_line
			(start 3.400044 -3.400044)
			(end -2.146046 -3.400044)
			(stroke
				(width 0.1524)
				(type default)
			)
			(layer "F.SilkS")
		)
		(fp_line
			(start -3.400044 3.400044)
			(end 3.400044 3.400044)
			(stroke
				(width 0.1)
				(type default)
			)
			(layer "F.Fab")
		)
		(fp_line
			(start 3.400044 3.400044)
			(end 3.400044 -3.400044)
			(stroke
				(width 0.1)
				(type default)
			)
			(layer "F.Fab")
		)
		(fp_line
			(start -3.400044 -3.400044)
			(end -3.400044 3.400044)
			(stroke
				(width 0.1)
				(type default)
			)
			(layer "F.Fab")
		)
		(fp_line
			(start 3.400044 -3.400044)
			(end -3.400044 -3.400044)
			(stroke
				(width 0.1)
				(type default)
			)
			(layer "F.Fab")
		)
		(pad "1" smd rect
			(at -2.70002 0 180)
			(size 1.6002 3.5052)
			(layers "F.Cu" "F.Mask" "F.Paste")
			(net "SW_P12V_P0V8_PEX1_FLT")
		)
		(pad "2" smd rect
			(at 2.70002 0 180)
			(size 1.6002 3.5052)
			(layers "F.Cu" "F.Mask" "F.Paste")
			(net "GND")
		)
	)
	(footprint ""
		(layer "F.Cu")
		(at 330.724764 -204.551534 90)
		(property "Reference" "OSC1"
			(at 1.898396 -4.233164 0)
			(unlocked yes)
			(layer "F.SilkS")
			(effects
				(font
					(size 0.7874 0.5842)
					(thickness 0.1524)
				)
				(justify left)
			)
		)
		(property "Value" ""
			(at 0 0 90)
			(layer "F.Fab")
			(effects
				(font
					(size 1.27 1.27)
				)
			)
		)
		(duplicate_pad_numbers_are_jumpers no)
		(fp_line
			(start 1.299972 -1.599946)
			(end 1.299972 1.599946)
			(stroke
				(width 0.1524)
				(type default)
			)
			(layer "F.SilkS")
		)
		(fp_line
			(start -1.299972 -1.599946)
			(end 1.299972 -1.599946)
			(stroke
				(width 0.1524)
				(type default)
			)
			(layer "F.SilkS")
		)
		(fp_line
			(start 1.299972 1.599946)
			(end -1.299972 1.599946)
			(stroke
				(width 0.1524)
				(type default)
			)
			(layer "F.SilkS")
		)
		(fp_line
			(start -1.299972 1.599946)
			(end -1.299972 -1.599946)
			(stroke
				(width 0.1524)
				(type default)
			)
			(layer "F.SilkS")
		)
		(fp_poly
			(pts
				(xy -1.84912 0.629412) (xy -2.567686 -0.0889) (xy -1.489964 -0.448056)
			)
			(stroke
				(width 0)
				(type default)
			)
			(fill yes)
			(layer "F.SilkS")
		)
		(fp_line
			(start 1.050036 -1.299972)
			(end 1.050036 1.299972)
			(stroke
				(width 0.1)
				(type default)
			)
			(layer "F.Fab")
		)
		(fp_line
			(start -1.050036 -1.299972)
			(end 1.050036 -1.299972)
			(stroke
				(width 0.1)
				(type default)
			)
			(layer "F.Fab")
		)
		(fp_line
			(start 1.050036 1.299972)
			(end -1.050036 1.299972)
			(stroke
				(width 0.1)
				(type default)
			)
			(layer "F.Fab")
		)
		(fp_line
			(start -1.050036 1.299972)
			(end -1.050036 -1.299972)
			(stroke
				(width 0.1)
				(type default)
			)
			(layer "F.Fab")
		)
		(fp_poly
			(pts
				(xy -2.4892 -0.24892) (xy -2.4892 -1.26492) (xy -1.4732 -0.75692)
			)
			(stroke
				(width 0)
				(type default)
			)
			(fill yes)
			(layer "F.Fab")
		)
		(pad "1" smd rect
			(at -0.649986 -0.849884 90)
			(size 1.016 1.2192)
			(layers "F.Cu" "F.Mask" "F.Paste")
			(net "PU_CLK_25M_FPGA_EN")
		)
		(pad "2" smd rect
			(at -0.649986 0.849884 90)
			(size 1.016 1.2192)
			(layers "F.Cu" "F.Mask" "F.Paste")
			(net "GND")
		)
		(pad "3" smd rect
			(at 0.649986 0.849884 90)
			(size 1.016 1.2192)
			(layers "F.Cu" "F.Mask" "F.Paste")
			(net "CLK_25M_FPGA")
		)
		(pad "4" smd rect
			(at 0.649986 -0.849884 90)
			(size 1.016 1.2192)
			(layers "F.Cu" "F.Mask" "F.Paste")
			(net "P3V3_AUX")
		)
	)
	(footprint ""
		(layer "F.Cu")
		(at 46.514512 -66.32194 90)
		(property "Reference" "R5834"
			(at 0 0 90)
			(layer "F.SilkS")
			(hide yes)
			(effects
				(font
					(size 1.27 1.27)
				)
			)
		)
		(property "Value" ""
			(at 0 0 90)
			(layer "F.Fab")
			(effects
				(font
					(size 1.27 1.27)
				)
			)
		)
		(duplicate_pad_numbers_are_jumpers no)
		(fp_line
			(start 0.7874 -0.4064)
			(end 0.7874 0.4064)
			(stroke
				(width 0.1524)
				(type default)
			)
			(layer "F.SilkS")
		)
		(fp_line
			(start -0.7874 -0.4064)
			(end 0.7874 -0.4064)
			(stroke
				(width 0.1524)
				(type default)
			)
			(layer "F.SilkS")
		)
		(fp_line
			(start 0.7874 0.4064)
			(end -0.7874 0.4064)
			(stroke
				(width 0.1524)
				(type default)
			)
			(layer "F.SilkS")
		)
		(fp_line
			(start -0.7874 0.4064)
			(end -0.7874 -0.4064)
			(stroke
				(width 0.1524)
				(type default)
			)
			(layer "F.SilkS")
		)
		(fp_line
			(start -0.12065 -0.305054)
			(end -0.12065 -0.2794)
			(stroke
				(width 0.1)
				(type default)
			)
			(layer "F.Fab")
		)
		(fp_line
			(start -0.67945 -0.305054)
			(end -0.12065 -0.305054)
			(stroke
				(width 0.1)
				(type default)
			)
			(layer "F.Fab")
		)
		(fp_line
			(start 0.67945 -0.3048)
			(end 0.67945 0.3048)
			(stroke
				(width 0.1)
				(type default)
			)
			(layer "F.Fab")
		)
		(fp_line
			(start 0.12065 -0.3048)
			(end 0.67945 -0.3048)
			(stroke
				(width 0.1)
				(type default)
			)
			(layer "F.Fab")
		)
		(fp_line
			(start 0.12065 -0.2794)
			(end 0.12065 -0.3048)
			(stroke
				(width 0.1)
				(type default)
			)
			(layer "F.Fab")
		)
		(fp_line
			(start -0.12065 -0.2794)
			(end 0.12065 -0.2794)
			(stroke
				(width 0.1)
				(type default)
			)
			(layer "F.Fab")
		)
		(fp_line
			(start 0.120396 0.2794)
			(end -0.12065 0.2794)
			(stroke
				(width 0.1)
				(type default)
			)
			(layer "F.Fab")
		)
		(fp_line
			(start -0.12065 0.2794)
			(end -0.12065 0.3048)
			(stroke
				(width 0.1)
				(type default)
			)
			(layer "F.Fab")
		)
		(fp_line
			(start 0.67945 0.3048)
			(end 0.120396 0.3048)
			(stroke
				(width 0.1)
				(type default)
			)
			(layer "F.Fab")
		)
		(fp_line
			(start 0.120396 0.3048)
			(end 0.120396 0.2794)
			(stroke
				(width 0.1)
				(type default)
			)
			(layer "F.Fab")
		)
		(fp_line
			(start -0.12065 0.3048)
			(end -0.67945 0.3048)
			(stroke
				(width 0.1)
				(type default)
			)
			(layer "F.Fab")
		)
		(fp_line
			(start -0.67945 0.3048)
			(end -0.67945 -0.305054)
			(stroke
				(width 0.1)
				(type default)
			)
			(layer "F.Fab")
		)
		(pad "1" smd circle
			(at -0.40005 0 90)
			(size 0 0)
			(layers "F.Cu" "F.Mask" "F.Paste")
			(net "SSD1_PWR_EN_R")
		)
		(pad "2" smd circle
			(at 0.40005 0 90)
			(size 0 0)
			(layers "F.Cu" "F.Mask" "F.Paste")
			(net "P12V_SSD1_CO_EN")
		)
	)
)
